#ISCELL
  mstr_symbols intel_corp_bpage *
  *
#ISCELL
  mstr_standard offpage *
  page134_i1
#CELL
  mstr_discrete fet_n *
  page134_i10
#CELL
  mstr_discrete res *
  page134_i11
#ISCELL
  mstr_symbols gnd *
  page134_i12
#ISCELL
  mstr_standard offpage *
  page134_i13
#ISCELL
  mstr_symbols p3v3_stby *
  page134_i2
#CELL
  mstr_discrete res *
  page134_i3
#CELL
  mstr_discrete fet_n *
  page134_i4
#ISCELL
  mstr_standard offpage *
  page134_i5
#ISCELL
  mstr_standard offpage *
  page134_i6
#ISCELL
  mstr_standard offpage *
  page134_i7
#ISCELL
  mstr_symbols p1v05_pch_stby *
  page134_i8
#CELL
  mstr_discrete res *
  page134_i9
